FILE_TYPE=LIBRARY_PARTS;
primitive 'SCONN75K_APCI0155P004A';
  pin
    '3.3V_1':
      PIN_NUMBER='(2)';
      PINUSE='POWER';
      NO_LOAD_CHECK='Both';
      NO_IO_CHECK='Both';
      NO_ASSERT_CHECK='TRUE';
      NO_DIR_CHECK='TRUE';
      ALLOW_CONNECT='TRUE';
    '3.3V_2':
      PIN_NUMBER='(4)';
      PINUSE='POWER';
      NO_LOAD_CHECK='Both';
      NO_IO_CHECK='Both';
      NO_ASSERT_CHECK='TRUE';
      NO_DIR_CHECK='TRUE';
      ALLOW_CONNECT='TRUE';
    'DAS_DSS#||LED1#':
      PIN_NUMBER='(10)';
      BIDIRECTIONAL='TRUE';
      INPUT_LOAD='(-0.01,0.01)';
      OUTPUT_LOAD='(1.0,-1.0)';
    '3.3V_3':
      PIN_NUMBER='(12)';
      PINUSE='POWER';
      NO_LOAD_CHECK='Both';
      NO_IO_CHECK='Both';
      NO_ASSERT_CHECK='TRUE';
      NO_DIR_CHECK='TRUE';
      ALLOW_CONNECT='TRUE';
    '3.3V_4':
      PIN_NUMBER='(14)';
      PINUSE='POWER';
      NO_LOAD_CHECK='Both';
      NO_IO_CHECK='Both';
      NO_ASSERT_CHECK='TRUE';
      NO_DIR_CHECK='TRUE';
      ALLOW_CONNECT='TRUE';
    '3.3V_5':
      PIN_NUMBER='(16)';
      PINUSE='POWER';
      NO_LOAD_CHECK='Both';
      NO_IO_CHECK='Both';
      NO_ASSERT_CHECK='TRUE';
      NO_DIR_CHECK='TRUE';
      ALLOW_CONNECT='TRUE';
    '3.3V_6':
      PIN_NUMBER='(18)';
      PINUSE='POWER';
      NO_LOAD_CHECK='Both';
      NO_IO_CHECK='Both';
      NO_ASSERT_CHECK='TRUE';
      NO_DIR_CHECK='TRUE';
      ALLOW_CONNECT='TRUE';
    'DEVSLP':
      PIN_NUMBER='(38)';
      INPUT_LOAD='(-0.01,0.01)';
    'PERST#':
      PIN_NUMBER='(50)';
      INPUT_LOAD='(-0.01,0.01)';
    'CLKREQ#':
      PIN_NUMBER='(52)';
      BIDIRECTIONAL='TRUE';
      INPUT_LOAD='(-0.01,0.01)';
      OUTPUT_LOAD='(1.0,-1.0)';
    'PEWAKE#':
      PIN_NUMBER='(54)';
      BIDIRECTIONAL='TRUE';
      INPUT_LOAD='(-0.01,0.01)';
      OUTPUT_LOAD='(1.0,-1.0)';
    'NC18':
      PIN_NUMBER='(58)';
      OUTPUT_TYPE='(TS,TS)';
      INPUT_LOAD='(-0.01,0.01)';
      OUTPUT_LOAD='(1.0,-1.0)';
    'SUSCLK':
      PIN_NUMBER='(68)';
      INPUT_LOAD='(-0.01,0.01)';
    '3.3V_7':
      PIN_NUMBER='(70)';
      PINUSE='POWER';
      NO_LOAD_CHECK='Both';
      NO_IO_CHECK='Both';
      NO_ASSERT_CHECK='TRUE';
      NO_DIR_CHECK='TRUE';
      ALLOW_CONNECT='TRUE';
    '3.3V_8':
      PIN_NUMBER='(72)';
      PINUSE='POWER';
      NO_LOAD_CHECK='Both';
      NO_IO_CHECK='Both';
      NO_ASSERT_CHECK='TRUE';
      NO_DIR_CHECK='TRUE';
      ALLOW_CONNECT='TRUE';
    '3.3V_9':
      PIN_NUMBER='(74)';
      PINUSE='POWER';
      NO_LOAD_CHECK='Both';
      NO_IO_CHECK='Both';
      NO_ASSERT_CHECK='TRUE';
      NO_DIR_CHECK='TRUE';
      ALLOW_CONNECT='TRUE';
    'PERN0||SATA-B+':
      PIN_NUMBER='(41)';
      BIDIRECTIONAL='TRUE';
      INPUT_LOAD='(-0.01,0.01)';
      OUTPUT_LOAD='(1.0,-1.0)';
    'PERP0||SATA-B-':
      PIN_NUMBER='(43)';
      BIDIRECTIONAL='TRUE';
      INPUT_LOAD='(-0.01,0.01)';
      OUTPUT_LOAD='(1.0,-1.0)';
    'PETN0||SATA-A-':
      PIN_NUMBER='(47)';
      BIDIRECTIONAL='TRUE';
      INPUT_LOAD='(-0.01,0.01)';
      OUTPUT_LOAD='(1.0,-1.0)';
    'PETP0||SATA-A+':
      PIN_NUMBER='(49)';
      BIDIRECTIONAL='TRUE';
      INPUT_LOAD='(-0.01,0.01)';
      OUTPUT_LOAD='(1.0,-1.0)';
    'GND11':
      PIN_NUMBER='(57)';
      PINUSE='POWER';
      NO_LOAD_CHECK='Both';
      NO_IO_CHECK='Both';
      NO_ASSERT_CHECK='TRUE';
      NO_DIR_CHECK='TRUE';
      ALLOW_CONNECT='TRUE';
    'NC19':
      PIN_NUMBER='(67)';
      OUTPUT_TYPE='(TS,TS)';
      INPUT_LOAD='(-0.01,0.01)';
      OUTPUT_LOAD='(1.0,-1.0)';
    'PEDET':
      PIN_NUMBER='(69)';
      OUTPUT_LOAD='(1.0,-1.0)';
    'GND12':
      PIN_NUMBER='(71)';
      PINUSE='POWER';
      NO_LOAD_CHECK='Both';
      NO_IO_CHECK='Both';
      NO_ASSERT_CHECK='TRUE';
      NO_DIR_CHECK='TRUE';
      ALLOW_CONNECT='TRUE';
    'GND13':
      PIN_NUMBER='(73)';
      PINUSE='POWER';
      NO_LOAD_CHECK='Both';
      NO_IO_CHECK='Both';
      NO_ASSERT_CHECK='TRUE';
      NO_DIR_CHECK='TRUE';
      ALLOW_CONNECT='TRUE';
    'GND14':
      PIN_NUMBER='(75)';
      PINUSE='POWER';
      NO_LOAD_CHECK='Both';
      NO_IO_CHECK='Both';
      NO_ASSERT_CHECK='TRUE';
      NO_DIR_CHECK='TRUE';
      ALLOW_CONNECT='TRUE';
    'G1':
      PIN_NUMBER='(G1)';
      PINUSE='POWER';
      NO_LOAD_CHECK='Both';
      NO_IO_CHECK='Both';
      NO_ASSERT_CHECK='TRUE';
      NO_DIR_CHECK='TRUE';
      ALLOW_CONNECT='TRUE';
    'G2':
      PIN_NUMBER='(G2)';
      PINUSE='POWER';
      NO_LOAD_CHECK='Both';
      NO_IO_CHECK='Both';
      NO_ASSERT_CHECK='TRUE';
      NO_DIR_CHECK='TRUE';
      ALLOW_CONNECT='TRUE';
    'NC1':
      PIN_NUMBER='(6)';
      OUTPUT_TYPE='(TS,TS)';
      INPUT_LOAD='(-0.01,0.01)';
      OUTPUT_LOAD='(1.0,-1.0)';
    'NC2':
      PIN_NUMBER='(8)';
      OUTPUT_TYPE='(TS,TS)';
      INPUT_LOAD='(-0.01,0.01)';
      OUTPUT_LOAD='(1.0,-1.0)';
    'NC3':
      PIN_NUMBER='(20)';
      OUTPUT_TYPE='(TS,TS)';
      INPUT_LOAD='(-0.01,0.01)';
      OUTPUT_LOAD='(1.0,-1.0)';
    'NC10':
      PIN_NUMBER='(34)';
      OUTPUT_TYPE='(TS,TS)';
      INPUT_LOAD='(-0.01,0.01)';
      OUTPUT_LOAD='(1.0,-1.0)';
    'NC17':
      PIN_NUMBER='(56)';
      OUTPUT_TYPE='(TS,TS)';
      INPUT_LOAD='(-0.01,0.01)';
      OUTPUT_LOAD='(1.0,-1.0)';
    'NC16':
      PIN_NUMBER='(48)';
      OUTPUT_TYPE='(TS,TS)';
      INPUT_LOAD='(-0.01,0.01)';
      OUTPUT_LOAD='(1.0,-1.0)';
    'NC15':
      PIN_NUMBER='(46)';
      OUTPUT_TYPE='(TS,TS)';
      INPUT_LOAD='(-0.01,0.01)';
      OUTPUT_LOAD='(1.0,-1.0)';
    'NC14':
      PIN_NUMBER='(44)';
      OUTPUT_TYPE='(TS,TS)';
      INPUT_LOAD='(-0.01,0.01)';
      OUTPUT_LOAD='(1.0,-1.0)';
    'NC13':
      PIN_NUMBER='(42)';
      OUTPUT_TYPE='(TS,TS)';
      INPUT_LOAD='(-0.01,0.01)';
      OUTPUT_LOAD='(1.0,-1.0)';
    'NC12':
      PIN_NUMBER='(40)';
      OUTPUT_TYPE='(TS,TS)';
      INPUT_LOAD='(-0.01,0.01)';
      OUTPUT_LOAD='(1.0,-1.0)';
    'NC11':
      PIN_NUMBER='(36)';
      OUTPUT_TYPE='(TS,TS)';
      INPUT_LOAD='(-0.01,0.01)';
      OUTPUT_LOAD='(1.0,-1.0)';
    'NC9':
      PIN_NUMBER='(32)';
      OUTPUT_TYPE='(TS,TS)';
      INPUT_LOAD='(-0.01,0.01)';
      OUTPUT_LOAD='(1.0,-1.0)';
    'NC8':
      PIN_NUMBER='(30)';
      OUTPUT_TYPE='(TS,TS)';
      INPUT_LOAD='(-0.01,0.01)';
      OUTPUT_LOAD='(1.0,-1.0)';
    'NC7':
      PIN_NUMBER='(28)';
      OUTPUT_TYPE='(TS,TS)';
      INPUT_LOAD='(-0.01,0.01)';
      OUTPUT_LOAD='(1.0,-1.0)';
    'NC6':
      PIN_NUMBER='(26)';
      OUTPUT_TYPE='(TS,TS)';
      INPUT_LOAD='(-0.01,0.01)';
      OUTPUT_LOAD='(1.0,-1.0)';
    'NC5':
      PIN_NUMBER='(24)';
      OUTPUT_TYPE='(TS,TS)';
      INPUT_LOAD='(-0.01,0.01)';
      OUTPUT_LOAD='(1.0,-1.0)';
    'NC4':
      PIN_NUMBER='(22)';
      OUTPUT_TYPE='(TS,TS)';
      INPUT_LOAD='(-0.01,0.01)';
      OUTPUT_LOAD='(1.0,-1.0)';
    'GND1':
      PIN_NUMBER='(1)';
      PINUSE='POWER';
      NO_LOAD_CHECK='Both';
      NO_IO_CHECK='Both';
      NO_ASSERT_CHECK='TRUE';
      NO_DIR_CHECK='TRUE';
      ALLOW_CONNECT='TRUE';
    'GND2':
      PIN_NUMBER='(3)';
      PINUSE='POWER';
      NO_LOAD_CHECK='Both';
      NO_IO_CHECK='Both';
      NO_ASSERT_CHECK='TRUE';
      NO_DIR_CHECK='TRUE';
      ALLOW_CONNECT='TRUE';
    'GND3':
      PIN_NUMBER='(9)';
      PINUSE='POWER';
      NO_LOAD_CHECK='Both';
      NO_IO_CHECK='Both';
      NO_ASSERT_CHECK='TRUE';
      NO_DIR_CHECK='TRUE';
      ALLOW_CONNECT='TRUE';
    'GND4':
      PIN_NUMBER='(15)';
      PINUSE='POWER';
      NO_LOAD_CHECK='Both';
      NO_IO_CHECK='Both';
      NO_ASSERT_CHECK='TRUE';
      NO_DIR_CHECK='TRUE';
      ALLOW_CONNECT='TRUE';
    'GND5':
      PIN_NUMBER='(21)';
      PINUSE='POWER';
      NO_LOAD_CHECK='Both';
      NO_IO_CHECK='Both';
      NO_ASSERT_CHECK='TRUE';
      NO_DIR_CHECK='TRUE';
      ALLOW_CONNECT='TRUE';
    'GND6':
      PIN_NUMBER='(27)';
      PINUSE='POWER';
      NO_LOAD_CHECK='Both';
      NO_IO_CHECK='Both';
      NO_ASSERT_CHECK='TRUE';
      NO_DIR_CHECK='TRUE';
      ALLOW_CONNECT='TRUE';
    'GND7':
      PIN_NUMBER='(33)';
      PINUSE='POWER';
      NO_LOAD_CHECK='Both';
      NO_IO_CHECK='Both';
      NO_ASSERT_CHECK='TRUE';
      NO_DIR_CHECK='TRUE';
      ALLOW_CONNECT='TRUE';
    'GND8':
      PIN_NUMBER='(39)';
      PINUSE='POWER';
      NO_LOAD_CHECK='Both';
      NO_IO_CHECK='Both';
      NO_ASSERT_CHECK='TRUE';
      NO_DIR_CHECK='TRUE';
      ALLOW_CONNECT='TRUE';
    'GND9':
      PIN_NUMBER='(45)';
      PINUSE='POWER';
      NO_LOAD_CHECK='Both';
      NO_IO_CHECK='Both';
      NO_ASSERT_CHECK='TRUE';
      NO_DIR_CHECK='TRUE';
      ALLOW_CONNECT='TRUE';
    'GND10':
      PIN_NUMBER='(51)';
      PINUSE='POWER';
      NO_LOAD_CHECK='Both';
      NO_IO_CHECK='Both';
      NO_ASSERT_CHECK='TRUE';
      NO_DIR_CHECK='TRUE';
      ALLOW_CONNECT='TRUE';
    'PERN3':
      PIN_NUMBER='(5)';
      BIDIRECTIONAL='TRUE';
      INPUT_LOAD='(-0.01,0.01)';
      OUTPUT_LOAD='(1.0,-1.0)';
    'PERP3':
      PIN_NUMBER='(7)';
      BIDIRECTIONAL='TRUE';
      INPUT_LOAD='(-0.01,0.01)';
      OUTPUT_LOAD='(1.0,-1.0)';
    'PETN3':
      PIN_NUMBER='(11)';
      BIDIRECTIONAL='TRUE';
      INPUT_LOAD='(-0.01,0.01)';
      OUTPUT_LOAD='(1.0,-1.0)';
    'PETP3':
      PIN_NUMBER='(13)';
      BIDIRECTIONAL='TRUE';
      INPUT_LOAD='(-0.01,0.01)';
      OUTPUT_LOAD='(1.0,-1.0)';
    'PERN2':
      PIN_NUMBER='(17)';
      BIDIRECTIONAL='TRUE';
      INPUT_LOAD='(-0.01,0.01)';
      OUTPUT_LOAD='(1.0,-1.0)';
    'PERP2':
      PIN_NUMBER='(19)';
      BIDIRECTIONAL='TRUE';
      INPUT_LOAD='(-0.01,0.01)';
      OUTPUT_LOAD='(1.0,-1.0)';
    'PETN2':
      PIN_NUMBER='(23)';
      BIDIRECTIONAL='TRUE';
      INPUT_LOAD='(-0.01,0.01)';
      OUTPUT_LOAD='(1.0,-1.0)';
    'PETP2':
      PIN_NUMBER='(25)';
      BIDIRECTIONAL='TRUE';
      INPUT_LOAD='(-0.01,0.01)';
      OUTPUT_LOAD='(1.0,-1.0)';
    'PERN1':
      PIN_NUMBER='(29)';
      BIDIRECTIONAL='TRUE';
      INPUT_LOAD='(-0.01,0.01)';
      OUTPUT_LOAD='(1.0,-1.0)';
    'PERP1':
      PIN_NUMBER='(31)';
      BIDIRECTIONAL='TRUE';
      INPUT_LOAD='(-0.01,0.01)';
      OUTPUT_LOAD='(1.0,-1.0)';
    'PETN1':
      PIN_NUMBER='(35)';
      BIDIRECTIONAL='TRUE';
      INPUT_LOAD='(-0.01,0.01)';
      OUTPUT_LOAD='(1.0,-1.0)';
    'PETP1':
      PIN_NUMBER='(37)';
      BIDIRECTIONAL='TRUE';
      INPUT_LOAD='(-0.01,0.01)';
      OUTPUT_LOAD='(1.0,-1.0)';
    'REFCLKN':
      PIN_NUMBER='(53)';
      INPUT_LOAD='(-0.01,0.01)';
    'REFCLKP':
      PIN_NUMBER='(55)';
      INPUT_LOAD='(-0.01,0.01)';
  end_pin;
  body
    PART_NAME='SCONN75K_APCI0155P004A';
    BODY_NAME='SCONN75K_APCI0155P004A';
    PHYS_DES_PREFIX='J';
    CLASS='IO';
    NC_PINS='(H1,H2)';
  end_body;
end_primitive;

END.
